# T6G (Grand Teton) — schematic netlist excerpt (pin names and nets, part order shuffled) for the footprints in the layout excerpt that follows; sources: Cadence DE-HDL packaged netlist, KiCad conversion of 04192023_DAF0TMB3IC0_F0TG_MB_C_brd_V02_OCP.brd

C247  Q_CAP  100UF 4V 20% X6S  pkg C0805  page 323 : A = P0V9_CPU1_RT0_2A ; B = GND
R339  Q_RES  49.9 1% EMPTY  pkg 0201LF  page 180 : A = USB2_CPU0_P0_DP ; B = GND
H124  HOLE  EMPTY  pkg TH  page 230 : \1\ = NC

DB8  TDR_3P  EMPTY  pkg TH2  page 260
  GND  = T1_GND
  IO1  = TDR_SE_50_OHM_IN1
  IO2  = TDR_SE_50_OHM_IN1

(kicad_pcb
	(version 20260206)
	(generator "pcbnew")
	(generator_version "10.0")
	(general
		(thickness 1.6)
		(legacy_teardrops no)
	)
	(paper "A4")
	(title_block
		(title "04192023_DAF0TMB3IC0_F0TG_MB_C_brd_V02_OCP.brd")
		(comment 1 "Grand Teton / footprints 122-125 of 8354")
	)
	(layers
		(0 "F.Cu" signal "TOP")
		(4 "In1.Cu" signal "GND")
		(6 "In2.Cu" signal "IN1")
		(8 "In3.Cu" signal "GND1")
		(10 "In4.Cu" signal "IN2")
		(12 "In5.Cu" signal "GND2")
		(14 "In6.Cu" signal "IN3")
		(16 "In7.Cu" signal "GND3")
		(18 "In8.Cu" signal "VCC")
		(20 "In9.Cu" signal "VCC1")
		(22 "In10.Cu" signal "GND4")
		(24 "In11.Cu" signal "IN4")
		(26 "In12.Cu" signal "GND5")
		(28 "In13.Cu" signal "IN5")
		(30 "In14.Cu" signal "GND6")
		(32 "In15.Cu" signal "IN6")
		(34 "In16.Cu" signal "GND7")
		(2 "B.Cu" signal "BOTTOM")
		(9 "F.Adhes" user "F.Adhesive")
		(11 "B.Adhes" user "B.Adhesive")
		(13 "F.Paste" user "Package Geometry/Pastemask Top")
		(15 "B.Paste" user "Package Geometry/Pastemask Bottom")
		(5 "F.SilkS" user "Ref Des/Silkscreen Top")
		(7 "B.SilkS" user "Ref Des/Silkscreen Bottom")
		(1 "F.Mask" user "Board Geometry/Soldermask Top")
		(3 "B.Mask" user "Board Geometry/Soldermask Bottom")
		(17 "Dwgs.User" user "User.Drawings")
		(19 "Cmts.User" user "User.Comments")
		(21 "Eco1.User" user "User.Eco1")
		(23 "Eco2.User" user "User.Eco2")
		(25 "Edge.Cuts" user "Board Geometry/Outline")
		(27 "Margin" user)
		(31 "F.CrtYd" user "Package Geometry/Place Bound Top")
		(29 "B.CrtYd" user "Package Geometry/Place Bound Bottom")
		(35 "F.Fab" user "Ref Des/Assembly Top")
		(33 "B.Fab" user "Ref Des/Assembly Bottom")
	)
	(footprint ""
		(layer "F.Cu")
		(at 130.23088 -27.25928 180)
		(property "Reference" "R339"
			(at 0 0 180)
			(layer "F.SilkS")
			(hide yes)
			(effects
				(font
					(size 1.27 1.27)
				)
			)
		)
		(property "Value" ""
			(at 0 0 180)
			(layer "F.Fab")
			(effects
				(font
					(size 1.27 1.27)
				)
			)
		)
		(duplicate_pad_numbers_are_jumpers no)
		(fp_line
			(start 0.32512 0.175006)
			(end -0.32512 0.175006)
			(stroke
				(width 0.1)
				(type default)
			)
			(layer "F.Fab")
		)
		(fp_line
			(start 0.32512 -0.175006)
			(end 0.32512 0.175006)
			(stroke
				(width 0.1)
				(type default)
			)
			(layer "F.Fab")
		)
		(fp_line
			(start -0.32512 0.175006)
			(end -0.32512 -0.175006)
			(stroke
				(width 0.1)
				(type default)
			)
			(layer "F.Fab")
		)
		(fp_line
			(start -0.32512 -0.175006)
			(end 0.32512 -0.175006)
			(stroke
				(width 0.1)
				(type default)
			)
			(layer "F.Fab")
		)
		(pad "1" smd rect
			(at -0.2667 0 180)
			(size 0.3048 0.381)
			(layers "F.Cu" "F.Mask" "F.Paste")
			(net "USB2_CPU0_P0_DP")
		)
		(pad "2" smd rect
			(at 0.2667 0)
			(size 0.3048 0.381)
			(layers "F.Cu" "F.Mask" "F.Paste")
			(net "GND")
		)
	)
	(footprint ""
		(layer "F.Cu")
		(at 473.706444 -353.119436)
		(property "Reference" "DB8"
			(at 1.09601 3.154934 0)
			(unlocked yes)
			(layer "F.SilkS")
			(effects
				(font
					(size 0.7874 0.5842)
					(thickness 0.1524)
				)
				(justify left)
			)
		)
		(property "Value" ""
			(at 0 0 0)
			(layer "F.Fab")
			(effects
				(font
					(size 1.27 1.27)
				)
			)
		)
		(duplicate_pad_numbers_are_jumpers no)
		(fp_line
			(start -3.330702 -4.771136)
			(end 3.330702 -4.771136)
			(stroke
				(width 0.1524)
				(type default)
			)
			(layer "F.SilkS")
		)
		(fp_line
			(start 0 4.011168)
			(end -3.330702 -4.771136)
			(stroke
				(width 0.1524)
				(type default)
			)
			(layer "F.SilkS")
		)
		(fp_line
			(start 2.71653 -3.151378)
			(end 0 4.011168)
			(stroke
				(width 0.1524)
				(type default)
			)
			(layer "F.SilkS")
		)
		(fp_line
			(start -3.330702 -4.771136)
			(end 3.330702 -4.771136)
			(stroke
				(width 0.1)
				(type default)
			)
			(layer "F.Fab")
		)
		(fp_line
			(start 0 4.011168)
			(end -3.330702 -4.771136)
			(stroke
				(width 0.1)
				(type default)
			)
			(layer "F.Fab")
		)
		(fp_line
			(start 3.330702 -4.771136)
			(end 0 4.011168)
			(stroke
				(width 0.1)
				(type default)
			)
			(layer "F.Fab")
		)
		(pad "1" thru_hole circle
			(at 0 0)
			(size 2.159 2.159)
			(drill 1.7018)
			(layers "*.Cu" "*.Mask")
			(remove_unused_layers no)
			(net "T1_GND")
			(clearance 0.0254)
			(thermal_gap 0.0254)
		)
		(pad "2" thru_hole circle
			(at -1.27 -3.348736)
			(size 2.159 2.159)
			(drill 1.7018)
			(layers "*.Cu" "*.Mask")
			(remove_unused_layers no)
			(net "TDR_SE_50_OHM_IN1")
			(clearance 0.0254)
			(thermal_gap 0.0254)
		)
		(pad "3" thru_hole circle
			(at 1.27 -3.348736)
			(size 2.159 2.159)
			(drill 1.7018)
			(layers "*.Cu" "*.Mask")
			(remove_unused_layers no)
			(net "TDR_SE_50_OHM_IN1")
			(clearance 0.0254)
			(thermal_gap 0.0254)
		)
	)
	(footprint ""
		(layer "F.Cu")
		(at 441.89523 -153.774394)
		(property "Reference" "H124"
			(at -3.257296 -7.931912 0)
			(unlocked yes)
			(layer "F.SilkS")
			(effects
				(font
					(size 0.7874 0.5842)
					(thickness 0.1524)
				)
				(justify left)
			)
		)
		(property "Value" ""
			(at 0 0 0)
			(layer "F.Fab")
			(effects
				(font
					(size 1.27 1.27)
				)
			)
		)
		(duplicate_pad_numbers_are_jumpers no)
		(fp_circle
			(center 0 0)
			(end 5.8166 0)
			(stroke
				(width 0.1524)
				(type default)
			)
			(fill no)
			(layer "F.SilkS")
		)
		(fp_circle
			(center 0 0)
			(end 5.8166 0)
			(stroke
				(width 0.1524)
				(type default)
			)
			(fill no)
			(layer "B.SilkS")
		)
		(fp_circle
			(center 0 0)
			(end 5.8166 0)
			(stroke
				(width 0.1)
				(type default)
			)
			(fill no)
			(layer "B.Fab")
		)
		(fp_circle
			(center 0 0)
			(end 5.8166 0)
			(stroke
				(width 0.1)
				(type default)
			)
			(fill no)
			(layer "F.Fab")
		)
		(pad "" np_thru_hole circle
			(at 0 0)
			(size 10.0076 10.0076)
			(drill 10.0076)
			(layers "*.Cu" "*.Mask")
			(clearance 0.381)
			(thermal_gap 0.381)
		)
	)
	(footprint ""
		(layer "F.Cu")
		(at 47.868586 -396.010892)
		(property "Reference" "C247"
			(at 0 0 0)
			(layer "F.SilkS")
			(hide yes)
			(effects
				(font
					(size 1.27 1.27)
				)
			)
		)
		(property "Value" ""
			(at 0 0 0)
			(layer "F.Fab")
			(effects
				(font
					(size 1.27 1.27)
				)
			)
		)
		(duplicate_pad_numbers_are_jumpers no)
		(fp_line
			(start -1.524 -0.762)
			(end 1.524 -0.762)
			(stroke
				(width 0.1524)
				(type default)
			)
			(layer "F.SilkS")
		)
		(fp_line
			(start -1.524 0.762)
			(end -1.524 -0.762)
			(stroke
				(width 0.1524)
				(type default)
			)
			(layer "F.SilkS")
		)
		(fp_line
			(start 1.524 -0.762)
			(end 1.524 0.762)
			(stroke
				(width 0.1524)
				(type default)
			)
			(layer "F.SilkS")
		)
		(fp_line
			(start 1.524 0.762)
			(end -1.524 0.762)
			(stroke
				(width 0.1524)
				(type default)
			)
			(layer "F.SilkS")
		)
		(fp_line
			(start -1.1049 -0.724916)
			(end -1.1049 0.724916)
			(stroke
				(width 0.1)
				(type default)
			)
			(layer "F.Fab")
		)
		(fp_line
			(start -1.1049 0.724916)
			(end 1.1049 0.724916)
			(stroke
				(width 0.1)
				(type default)
			)
			(layer "F.Fab")
		)
		(fp_line
			(start 1.1049 -0.724916)
			(end -1.1049 -0.724916)
			(stroke
				(width 0.1)
				(type default)
			)
			(layer "F.Fab")
		)
		(fp_line
			(start 1.1049 0.724916)
			(end 1.1049 -0.724916)
			(stroke
				(width 0.1)
				(type default)
			)
			(layer "F.Fab")
		)
		(pad "1" smd rect
			(at -0.889 0 180)
			(size 1.016 1.27)
			(layers "F.Cu" "F.Mask" "F.Paste")
			(net "P0V9_CPU1_RT0_2A")
		)
		(pad "2" smd rect
			(at 0.889 0 180)
			(size 1.016 1.27)
			(layers "F.Cu" "F.Mask" "F.Paste")
			(net "GND")
		)
	)
)
